# SCM (Grand Teton) — schematic netlist excerpt (pin names and nets, part order shuffled) for the footprints in the layout excerpt that follows; sources: Cadence DE-HDL packaged netlist, KiCad conversion of 12092022_DA0F0TMDCD0_F0T_Management_Board_D_brd_V3_OCP.brd

U3  FSA3357K8X  IC  pkg US8_0-5_2X2-3_EOL  page 30
  B0  = UART_BIC_DBG_RX
  B1  = UART_BMC_5_RXD_BUF1_SW
  B2  = UART_BMC_1_RXD_R
  GND  = GND
  S2  = FM_UARTSW_LSB_N
  S1  = FM_UARTSW_MSB_N
  A  = SPA_SIN_SW_BUF
  VCC  = P3V3_AUX

R651  Q_RES  33.2 1% EMPTY  pkg 0402LF  page 21 : A = BMC_EMMC_DT6 ; B = EMMC_DT6_R

(kicad_pcb
	(version 20260206)
	(generator "pcbnew")
	(generator_version "10.0")
	(general
		(thickness 1.6)
		(legacy_teardrops no)
	)
	(paper "A4")
	(title_block
		(title "12092022_DA0F0TMDCD0_F0T_Management_Board_D_brd_V3_OCP.brd")
		(comment 1 "Grand Teton / footprints 163-164 of 1440")
	)
	(layers
		(0 "F.Cu" signal "TOP")
		(4 "In1.Cu" signal "GND")
		(6 "In2.Cu" signal "IN1")
		(8 "In3.Cu" signal "GND1")
		(10 "In4.Cu" signal "IN2")
		(12 "In5.Cu" signal "VCC")
		(14 "In6.Cu" signal "VCC1")
		(16 "In7.Cu" signal "IN3")
		(18 "In8.Cu" signal "GND2")
		(20 "In9.Cu" signal "IN4")
		(22 "In10.Cu" signal "GND3")
		(2 "B.Cu" signal "BOTTOM")
		(9 "F.Adhes" user "F.Adhesive")
		(11 "B.Adhes" user "B.Adhesive")
		(13 "F.Paste" user "Package Geometry/Pastemask Top")
		(15 "B.Paste" user "Package Geometry/Pastemask Bottom")
		(5 "F.SilkS" user "Ref Des/Silkscreen Top")
		(7 "B.SilkS" user "Ref Des/Silkscreen Bottom")
		(1 "F.Mask" user "Board Geometry/Soldermask Top")
		(3 "B.Mask" user "Board Geometry/Soldermask Bottom")
		(17 "Dwgs.User" user "User.Drawings")
		(19 "Cmts.User" user "User.Comments")
		(21 "Eco1.User" user "User.Eco1")
		(23 "Eco2.User" user "User.Eco2")
		(25 "Edge.Cuts" user "Board Geometry/Outline")
		(27 "Margin" user)
		(31 "F.CrtYd" user "Package Geometry/Place Bound Top")
		(29 "B.CrtYd" user "Package Geometry/Place Bound Bottom")
		(35 "F.Fab" user "Ref Des/Assembly Top")
		(33 "B.Fab" user "Ref Des/Assembly Bottom")
	)
	(footprint ""
		(layer "F.Cu")
		(at 19.4056 -62.3316 90)
		(property "Reference" "U3"
			(at -1.8288 -1.61163 90)
			(unlocked yes)
			(layer "F.SilkS")
			(effects
				(font
					(size 0.7874 0.5842)
					(thickness 0.1524)
				)
				(justify left)
			)
		)
		(property "Value" ""
			(at 0 0 90)
			(layer "F.Fab")
			(effects
				(font
					(size 1.27 1.27)
				)
			)
		)
		(duplicate_pad_numbers_are_jumpers no)
		(fp_line
			(start 0.8636 -1.050036)
			(end 0.542036 -1.050036)
			(stroke
				(width 0.1524)
				(type default)
			)
			(layer "F.SilkS")
		)
		(fp_line
			(start 0.542036 -1.050036)
			(end 0 -0.508)
			(stroke
				(width 0.1524)
				(type default)
			)
			(layer "F.SilkS")
		)
		(fp_line
			(start -0.542036 -1.050036)
			(end -0.8636 -1.050036)
			(stroke
				(width 0.1524)
				(type default)
			)
			(layer "F.SilkS")
		)
		(fp_line
			(start -0.8636 -1.050036)
			(end -0.8636 1.050036)
			(stroke
				(width 0.1524)
				(type default)
			)
			(layer "F.SilkS")
		)
		(fp_line
			(start 0 -0.508)
			(end -0.542036 -1.050036)
			(stroke
				(width 0.1524)
				(type default)
			)
			(layer "F.SilkS")
		)
		(fp_line
			(start 0.8636 1.050036)
			(end 0.8636 -1.050036)
			(stroke
				(width 0.1524)
				(type default)
			)
			(layer "F.SilkS")
		)
		(fp_line
			(start -0.8636 1.050036)
			(end 0.8636 1.050036)
			(stroke
				(width 0.1524)
				(type default)
			)
			(layer "F.SilkS")
		)
		(fp_poly
			(pts
				(xy -2.201672 -1.857248) (xy -2.919984 -1.138936) (xy -1.842262 -0.77978)
			)
			(stroke
				(width 0)
				(type default)
			)
			(fill yes)
			(layer "F.SilkS")
		)
		(fp_line
			(start 1.199896 -1.050036)
			(end -1.199896 -1.050036)
			(stroke
				(width 0.1)
				(type default)
			)
			(layer "F.Fab")
		)
		(fp_line
			(start -1.199896 -1.050036)
			(end -1.199896 1.050036)
			(stroke
				(width 0.1)
				(type default)
			)
			(layer "F.Fab")
		)
		(fp_line
			(start 1.199896 1.050036)
			(end 1.199896 -1.050036)
			(stroke
				(width 0.1)
				(type default)
			)
			(layer "F.Fab")
		)
		(fp_line
			(start -1.199896 1.050036)
			(end 1.199896 1.050036)
			(stroke
				(width 0.1)
				(type default)
			)
			(layer "F.Fab")
		)
		(fp_poly
			(pts
				(xy -2.794 -1.258062) (xy -2.794 -0.242062) (xy -1.778 -0.750062)
			)
			(stroke
				(width 0)
				(type default)
			)
			(fill yes)
			(layer "F.Fab")
		)
		(pad "1" smd rect
			(at -1.35001 -0.750062)
			(size 0.2794 0.7112)
			(layers "F.Cu" "F.Mask" "F.Paste")
			(net "UART_BIC_DBG_RX")
		)
		(pad "2" smd rect
			(at -1.35001 -0.249936)
			(size 0.2794 0.7112)
			(layers "F.Cu" "F.Mask" "F.Paste")
			(net "UART_BMC_5_RXD_BUF1_SW")
		)
		(pad "3" smd rect
			(at -1.35001 0.249936)
			(size 0.2794 0.7112)
			(layers "F.Cu" "F.Mask" "F.Paste")
			(net "UART_BMC_1_RXD_R")
		)
		(pad "4" smd rect
			(at -1.35001 0.750062)
			(size 0.2794 0.7112)
			(layers "F.Cu" "F.Mask" "F.Paste")
			(net "GND")
		)
		(pad "5" smd rect
			(at 1.35001 0.750062)
			(size 0.2794 0.7112)
			(layers "F.Cu" "F.Mask" "F.Paste")
			(net "FM_UARTSW_LSB_N")
		)
		(pad "6" smd rect
			(at 1.35001 0.249936)
			(size 0.2794 0.7112)
			(layers "F.Cu" "F.Mask" "F.Paste")
			(net "FM_UARTSW_MSB_N")
		)
		(pad "7" smd rect
			(at 1.35001 -0.249936)
			(size 0.2794 0.7112)
			(layers "F.Cu" "F.Mask" "F.Paste")
			(net "SPA_SIN_SW_BUF")
		)
		(pad "8" smd rect
			(at 1.35001 -0.750062)
			(size 0.2794 0.7112)
			(layers "F.Cu" "F.Mask" "F.Paste")
			(net "P3V3_AUX")
		)
	)
	(footprint ""
		(layer "F.Cu")
		(at 30.41904 -70.536054 90)
		(property "Reference" "R651"
			(at 0 0 90)
			(layer "F.SilkS")
			(hide yes)
			(effects
				(font
					(size 1.27 1.27)
				)
			)
		)
		(property "Value" ""
			(at 0 0 90)
			(layer "F.Fab")
			(effects
				(font
					(size 1.27 1.27)
				)
			)
		)
		(duplicate_pad_numbers_are_jumpers no)
		(fp_line
			(start 0.7874 -0.4064)
			(end 0.7874 0.4064)
			(stroke
				(width 0.1524)
				(type default)
			)
			(layer "F.SilkS")
		)
		(fp_line
			(start -0.7874 -0.4064)
			(end 0.7874 -0.4064)
			(stroke
				(width 0.1524)
				(type default)
			)
			(layer "F.SilkS")
		)
		(fp_line
			(start 0.7874 0.4064)
			(end -0.7874 0.4064)
			(stroke
				(width 0.1524)
				(type default)
			)
			(layer "F.SilkS")
		)
		(fp_line
			(start -0.7874 0.4064)
			(end -0.7874 -0.4064)
			(stroke
				(width 0.1524)
				(type default)
			)
			(layer "F.SilkS")
		)
		(fp_line
			(start -0.12065 -0.305054)
			(end -0.12065 -0.2794)
			(stroke
				(width 0.1)
				(type default)
			)
			(layer "F.Fab")
		)
		(fp_line
			(start -0.67945 -0.305054)
			(end -0.12065 -0.305054)
			(stroke
				(width 0.1)
				(type default)
			)
			(layer "F.Fab")
		)
		(fp_line
			(start 0.67945 -0.3048)
			(end 0.67945 0.3048)
			(stroke
				(width 0.1)
				(type default)
			)
			(layer "F.Fab")
		)
		(fp_line
			(start 0.12065 -0.3048)
			(end 0.67945 -0.3048)
			(stroke
				(width 0.1)
				(type default)
			)
			(layer "F.Fab")
		)
		(fp_line
			(start 0.12065 -0.2794)
			(end 0.12065 -0.3048)
			(stroke
				(width 0.1)
				(type default)
			)
			(layer "F.Fab")
		)
		(fp_line
			(start -0.12065 -0.2794)
			(end 0.12065 -0.2794)
			(stroke
				(width 0.1)
				(type default)
			)
			(layer "F.Fab")
		)
		(fp_line
			(start 0.120396 0.2794)
			(end -0.12065 0.2794)
			(stroke
				(width 0.1)
				(type default)
			)
			(layer "F.Fab")
		)
		(fp_line
			(start -0.12065 0.2794)
			(end -0.12065 0.3048)
			(stroke
				(width 0.1)
				(type default)
			)
			(layer "F.Fab")
		)
		(fp_line
			(start 0.67945 0.3048)
			(end 0.120396 0.3048)
			(stroke
				(width 0.1)
				(type default)
			)
			(layer "F.Fab")
		)
		(fp_line
			(start 0.120396 0.3048)
			(end 0.120396 0.2794)
			(stroke
				(width 0.1)
				(type default)
			)
			(layer "F.Fab")
		)
		(fp_line
			(start -0.12065 0.3048)
			(end -0.67945 0.3048)
			(stroke
				(width 0.1)
				(type default)
			)
			(layer "F.Fab")
		)
		(fp_line
			(start -0.67945 0.3048)
			(end -0.67945 -0.305054)
			(stroke
				(width 0.1)
				(type default)
			)
			(layer "F.Fab")
		)
		(pad "1" smd circle
			(at -0.40005 0 90)
			(size 0 0)
			(layers "F.Cu" "F.Mask" "F.Paste")
			(net "BMC_EMMC_DT6")
		)
		(pad "2" smd circle
			(at 0.40005 0 90)
			(size 0 0)
			(layers "F.Cu" "F.Mask" "F.Paste")
			(net "EMMC_DT6_R")
		)
	)
)
